# S9S_MB_2U (Grand Teton) — schematic netlist excerpt (pin names and nets, part order shuffled) for the footprints in the layout excerpt that follows; sources: Cadence DE-HDL packaged netlist, KiCad conversion of 03242023_DA0F0TMBIJ0_F0T_Motherboard_J_brd_V01_OCP.brd

PC180  Q_CAP  22UF 16V 20% X6S  pkg C0805  page 276 : A = SW_P12V_PVCCINFAON_CPU0_FLT ; B = GND
PC2236  Q_CAP  0.01UF 50V 10% EMPTY  pkg C0402  page 242 : A = P12V_SCM_R ; B = P12V_SCM_GATE
R3639  Q_RES  10K 1% CHIP  pkg 0402LF  page 208 : A = P3V3_AUX ; B = CK440Q_OE_2

(kicad_pcb
	(version 20260206)
	(generator "pcbnew")
	(generator_version "10.0")
	(general
		(thickness 1.6)
		(legacy_teardrops no)
	)
	(paper "A4")
	(title_block
		(title "03242023_DA0F0TMBIJ0_F0T_Motherboard_J_brd_V01_OCP.brd")
		(comment 1 "Grand Teton / footprints 2163-2165 of 6105")
	)
	(layers
		(0 "F.Cu" signal "TOP")
		(4 "In1.Cu" signal "GND")
		(6 "In2.Cu" signal "IN1")
		(8 "In3.Cu" signal "GND1")
		(10 "In4.Cu" signal "IN2")
		(12 "In5.Cu" signal "GND2")
		(14 "In6.Cu" signal "IN3")
		(16 "In7.Cu" signal "GND3")
		(18 "In8.Cu" signal "VCC")
		(20 "In9.Cu" signal "VCC1")
		(22 "In10.Cu" signal "GND4")
		(24 "In11.Cu" signal "IN4")
		(26 "In12.Cu" signal "GND5")
		(28 "In13.Cu" signal "IN5")
		(30 "In14.Cu" signal "GND6")
		(32 "In15.Cu" signal "IN6")
		(34 "In16.Cu" signal "GND7")
		(2 "B.Cu" signal "BOTTOM")
		(9 "F.Adhes" user "F.Adhesive")
		(11 "B.Adhes" user "B.Adhesive")
		(13 "F.Paste" user "Package Geometry/Pastemask Top")
		(15 "B.Paste" user "Package Geometry/Pastemask Bottom")
		(5 "F.SilkS" user "Ref Des/Silkscreen Top")
		(7 "B.SilkS" user "Ref Des/Silkscreen Bottom")
		(1 "F.Mask" user "Board Geometry/Soldermask Top")
		(3 "B.Mask" user "Board Geometry/Soldermask Bottom")
		(17 "Dwgs.User" user "User.Drawings")
		(19 "Cmts.User" user "User.Comments")
		(21 "Eco1.User" user "User.Eco1")
		(23 "Eco2.User" user "User.Eco2")
		(25 "Edge.Cuts" user "Board Geometry/Outline")
		(27 "Margin" user)
		(31 "F.CrtYd" user "Package Geometry/Place Bound Top")
		(29 "B.CrtYd" user "Package Geometry/Place Bound Bottom")
		(35 "F.Fab" user "Ref Des/Assembly Top")
		(33 "B.Fab" user "Ref Des/Assembly Bottom")
	)
	(footprint ""
		(layer "F.Cu")
		(at 424.511724 -149.239224 -90)
		(property "Reference" "PC180"
			(at 0 0 270)
			(layer "F.SilkS")
			(hide yes)
			(effects
				(font
					(size 1.27 1.27)
				)
			)
		)
		(property "Value" ""
			(at 0 0 270)
			(layer "F.Fab")
			(effects
				(font
					(size 1.27 1.27)
				)
			)
		)
		(duplicate_pad_numbers_are_jumpers no)
		(fp_line
			(start -1.524 0.762)
			(end -1.524 -0.762)
			(stroke
				(width 0.1524)
				(type default)
			)
			(layer "F.SilkS")
		)
		(fp_line
			(start 1.524 0.762)
			(end -1.524 0.762)
			(stroke
				(width 0.1524)
				(type default)
			)
			(layer "F.SilkS")
		)
		(fp_line
			(start -1.524 -0.762)
			(end 1.524 -0.762)
			(stroke
				(width 0.1524)
				(type default)
			)
			(layer "F.SilkS")
		)
		(fp_line
			(start 1.524 -0.762)
			(end 1.524 0.762)
			(stroke
				(width 0.1524)
				(type default)
			)
			(layer "F.SilkS")
		)
		(fp_line
			(start -1.1049 0.724916)
			(end 1.1049 0.724916)
			(stroke
				(width 0.1)
				(type default)
			)
			(layer "F.Fab")
		)
		(fp_line
			(start 1.1049 0.724916)
			(end 1.1049 -0.724916)
			(stroke
				(width 0.1)
				(type default)
			)
			(layer "F.Fab")
		)
		(fp_line
			(start -1.1049 -0.724916)
			(end -1.1049 0.724916)
			(stroke
				(width 0.1)
				(type default)
			)
			(layer "F.Fab")
		)
		(fp_line
			(start 1.1049 -0.724916)
			(end -1.1049 -0.724916)
			(stroke
				(width 0.1)
				(type default)
			)
			(layer "F.Fab")
		)
		(pad "1" smd rect
			(at -0.889 0 90)
			(size 1.016 1.27)
			(layers "F.Cu" "F.Mask" "F.Paste")
			(net "SW_P12V_PVCCINFAON_CPU0_FLT")
		)
		(pad "2" smd rect
			(at 0.889 0 90)
			(size 1.016 1.27)
			(layers "F.Cu" "F.Mask" "F.Paste")
			(net "GND")
		)
	)
	(footprint ""
		(layer "F.Cu")
		(at 191.295782 -29.283152 180)
		(property "Reference" "PC2236"
			(at 0 0 180)
			(layer "F.SilkS")
			(hide yes)
			(effects
				(font
					(size 1.27 1.27)
				)
			)
		)
		(property "Value" ""
			(at 0 0 180)
			(layer "F.Fab")
			(effects
				(font
					(size 1.27 1.27)
				)
			)
		)
		(duplicate_pad_numbers_are_jumpers no)
		(fp_line
			(start 0.7874 0.4064)
			(end -0.7874 0.4064)
			(stroke
				(width 0.1524)
				(type default)
			)
			(layer "F.SilkS")
		)
		(fp_line
			(start 0.7874 -0.4064)
			(end 0.7874 0.4064)
			(stroke
				(width 0.1524)
				(type default)
			)
			(layer "F.SilkS")
		)
		(fp_line
			(start -0.7874 0.4064)
			(end -0.7874 -0.4064)
			(stroke
				(width 0.1524)
				(type default)
			)
			(layer "F.SilkS")
		)
		(fp_line
			(start -0.7874 -0.4064)
			(end 0.7874 -0.4064)
			(stroke
				(width 0.1524)
				(type default)
			)
			(layer "F.SilkS")
		)
		(fp_line
			(start 0.67945 0.3048)
			(end 0.120396 0.3048)
			(stroke
				(width 0.1)
				(type default)
			)
			(layer "F.Fab")
		)
		(fp_line
			(start 0.67945 -0.3048)
			(end 0.67945 0.3048)
			(stroke
				(width 0.1)
				(type default)
			)
			(layer "F.Fab")
		)
		(fp_line
			(start 0.12065 -0.2794)
			(end 0.12065 -0.3048)
			(stroke
				(width 0.1)
				(type default)
			)
			(layer "F.Fab")
		)
		(fp_line
			(start 0.12065 -0.3048)
			(end 0.67945 -0.3048)
			(stroke
				(width 0.1)
				(type default)
			)
			(layer "F.Fab")
		)
		(fp_line
			(start 0.120396 0.3048)
			(end 0.120396 0.2794)
			(stroke
				(width 0.1)
				(type default)
			)
			(layer "F.Fab")
		)
		(fp_line
			(start 0.120396 0.2794)
			(end -0.12065 0.2794)
			(stroke
				(width 0.1)
				(type default)
			)
			(layer "F.Fab")
		)
		(fp_line
			(start -0.12065 0.3048)
			(end -0.67945 0.3048)
			(stroke
				(width 0.1)
				(type default)
			)
			(layer "F.Fab")
		)
		(fp_line
			(start -0.12065 0.2794)
			(end -0.12065 0.3048)
			(stroke
				(width 0.1)
				(type default)
			)
			(layer "F.Fab")
		)
		(fp_line
			(start -0.12065 -0.2794)
			(end 0.12065 -0.2794)
			(stroke
				(width 0.1)
				(type default)
			)
			(layer "F.Fab")
		)
		(fp_line
			(start -0.12065 -0.305054)
			(end -0.12065 -0.2794)
			(stroke
				(width 0.1)
				(type default)
			)
			(layer "F.Fab")
		)
		(fp_line
			(start -0.67945 0.3048)
			(end -0.67945 -0.305054)
			(stroke
				(width 0.1)
				(type default)
			)
			(layer "F.Fab")
		)
		(fp_line
			(start -0.67945 -0.305054)
			(end -0.12065 -0.305054)
			(stroke
				(width 0.1)
				(type default)
			)
			(layer "F.Fab")
		)
		(pad "1" smd circle
			(at -0.40005 0 180)
			(size 0 0)
			(layers "F.Cu" "F.Mask" "F.Paste")
			(net "P12V_SCM_R")
		)
		(pad "2" smd circle
			(at 0.40005 0 180)
			(size 0 0)
			(layers "F.Cu" "F.Mask" "F.Paste")
			(net "P12V_SCM_GATE")
		)
	)
	(footprint ""
		(layer "F.Cu")
		(at 260.593332 -92.497656 90)
		(property "Reference" "R3639"
			(at 0 0 90)
			(layer "F.SilkS")
			(hide yes)
			(effects
				(font
					(size 1.27 1.27)
				)
			)
		)
		(property "Value" ""
			(at 0 0 90)
			(layer "F.Fab")
			(effects
				(font
					(size 1.27 1.27)
				)
			)
		)
		(duplicate_pad_numbers_are_jumpers no)
		(fp_line
			(start 0.7874 -0.4064)
			(end 0.7874 0.4064)
			(stroke
				(width 0.1524)
				(type default)
			)
			(layer "F.SilkS")
		)
		(fp_line
			(start -0.7874 -0.4064)
			(end 0.7874 -0.4064)
			(stroke
				(width 0.1524)
				(type default)
			)
			(layer "F.SilkS")
		)
		(fp_line
			(start 0.7874 0.4064)
			(end -0.7874 0.4064)
			(stroke
				(width 0.1524)
				(type default)
			)
			(layer "F.SilkS")
		)
		(fp_line
			(start -0.7874 0.4064)
			(end -0.7874 -0.4064)
			(stroke
				(width 0.1524)
				(type default)
			)
			(layer "F.SilkS")
		)
		(fp_line
			(start -0.12065 -0.305054)
			(end -0.12065 -0.2794)
			(stroke
				(width 0.1)
				(type default)
			)
			(layer "F.Fab")
		)
		(fp_line
			(start -0.67945 -0.305054)
			(end -0.12065 -0.305054)
			(stroke
				(width 0.1)
				(type default)
			)
			(layer "F.Fab")
		)
		(fp_line
			(start 0.67945 -0.3048)
			(end 0.67945 0.3048)
			(stroke
				(width 0.1)
				(type default)
			)
			(layer "F.Fab")
		)
		(fp_line
			(start 0.12065 -0.3048)
			(end 0.67945 -0.3048)
			(stroke
				(width 0.1)
				(type default)
			)
			(layer "F.Fab")
		)
		(fp_line
			(start 0.12065 -0.2794)
			(end 0.12065 -0.3048)
			(stroke
				(width 0.1)
				(type default)
			)
			(layer "F.Fab")
		)
		(fp_line
			(start -0.12065 -0.2794)
			(end 0.12065 -0.2794)
			(stroke
				(width 0.1)
				(type default)
			)
			(layer "F.Fab")
		)
		(fp_line
			(start 0.120396 0.2794)
			(end -0.12065 0.2794)
			(stroke
				(width 0.1)
				(type default)
			)
			(layer "F.Fab")
		)
		(fp_line
			(start -0.12065 0.2794)
			(end -0.12065 0.3048)
			(stroke
				(width 0.1)
				(type default)
			)
			(layer "F.Fab")
		)
		(fp_line
			(start 0.67945 0.3048)
			(end 0.120396 0.3048)
			(stroke
				(width 0.1)
				(type default)
			)
			(layer "F.Fab")
		)
		(fp_line
			(start 0.120396 0.3048)
			(end 0.120396 0.2794)
			(stroke
				(width 0.1)
				(type default)
			)
			(layer "F.Fab")
		)
		(fp_line
			(start -0.12065 0.3048)
			(end -0.67945 0.3048)
			(stroke
				(width 0.1)
				(type default)
			)
			(layer "F.Fab")
		)
		(fp_line
			(start -0.67945 0.3048)
			(end -0.67945 -0.305054)
			(stroke
				(width 0.1)
				(type default)
			)
			(layer "F.Fab")
		)
		(pad "1" smd circle
			(at -0.40005 0 90)
			(size 0 0)
			(layers "F.Cu" "F.Mask" "F.Paste")
			(net "P3V3_AUX")
		)
		(pad "2" smd circle
			(at 0.40005 0 90)
			(size 0 0)
			(layers "F.Cu" "F.Mask" "F.Paste")
			(net "CK440Q_OE_2")
		)
	)
)
